FILE_TYPE = MACRO_DRAWING;
SET COLOR_WIRE YELLOW;
SET COLOR_PROP ORANGE;
SET COLOR_DOT WHITE;
SET COLOR_ARC YELLOW;
SET COLOR_BODY GREEN;
SET COLOR_NOTE PURPLE;
SET PROP_DISPLAY VALUE;
SET PAGE_NUMBER P16;
FORCEADD SOCKET4677_AZIF0045P001C01CS..4
(1025 2875);
FORCEPROP 1 LAST PART_NUMBER DGA^7000023
J 0
(-75 3825);
DISPLAY 0.723404 (-75 3825);
PAINT GREEN (-75 3825);
DISPLAY INVISIBLE (-75 3825);
FORCEPROP 2 LAST PART_TYPE SMLF
J 0
(-75 4000);
DISPLAY 1.021277 (-75 4000);
FORCEPROP 1 LAST MATERIAL IO
J 0
(-75 3750);
DISPLAY 0.723404 (-75 3750);
PAINT GREEN (-75 3750);
FORCEPROP 2 LAST VALUE SOCKET4677_AZIF0045-P001C01CS
J 0
(-75 3950);
DISPLAY 1.021277 (-75 3950);
FORCEPROP 1 LAST $LOCATION U2
J 0
(-75 3900);
DISPLAY 0.723404 (-75 3900);
PAINT GREEN (-75 3900);
FORCEPROP 0 LASTPIN (2250 2625) $PN BL23
J 0
(2260 2635);
DISPLAY 0.680851 (2260 2635);
PAINT MONO (2260 2635);
FORCEPROP 0 LASTPIN (2250 2575) $PN BN25
J 0
(2260 2585);
DISPLAY 0.680851 (2260 2585);
PAINT MONO (2260 2585);
FORCEPROP 0 LASTPIN (2250 2525) $PN BJ23
J 0
(2260 2535);
DISPLAY 0.680851 (2260 2535);
PAINT MONO (2260 2535);
FORCEPROP 0 LASTPIN (2250 2475) $PN BK24
J 0
(2260 2485);
DISPLAY 0.680851 (2260 2485);
PAINT MONO (2260 2485);
FORCEPROP 0 LASTPIN (-200 2525) $PN BD24
J 2
(-210 2535);
DISPLAY 0.680851 (-210 2535);
PAINT MONO (-210 2535);
FORCEPROP 0 LASTPIN (2250 3075) $PN BH22
J 0
(2260 3085);
DISPLAY 0.680851 (2260 3085);
PAINT MONO (2260 3085);
FORCEPROP 0 LASTPIN (-200 2375) $PN BU11
J 2
(-210 2385);
DISPLAY 0.680851 (-210 2385);
PAINT MONO (-210 2385);
FORCEPROP 0 LASTPIN (-200 2225) $PN AY85
J 2
(-210 2235);
DISPLAY 0.680851 (-210 2235);
PAINT MONO (-210 2235);
FORCEPROP 0 LASTPIN (-200 2975) $PN AU11
J 2
(-210 2985);
DISPLAY 0.680851 (-210 2985);
PAINT MONO (-210 2985);
FORCEPROP 0 LASTPIN (-200 2825) $PN BD87
J 2
(-210 2835);
DISPLAY 0.680851 (-210 2835);
PAINT MONO (-210 2835);
FORCEPROP 0 LASTPIN (-200 2675) $PN CA11
J 2
(-210 2685);
DISPLAY 0.680851 (-210 2685);
PAINT MONO (-210 2685);
FORCEPROP 0 LASTPIN (-200 2925) $PN BA11
J 2
(-210 2935);
DISPLAY 0.680851 (-210 2935);
PAINT MONO (-210 2935);
FORCEPROP 0 LASTPIN (-200 2775) $PN BC90
J 2
(-210 2785);
DISPLAY 0.680851 (-210 2785);
PAINT MONO (-210 2785);
FORCEPROP 0 LASTPIN (-200 2625) $PN CE11
J 2
(-210 2635);
DISPLAY 0.680851 (-210 2635);
PAINT MONO (-210 2635);
FORCEPROP 0 LASTPIN (-200 3375) $PN AU33
J 2
(-210 3385);
DISPLAY 0.680851 (-210 3385);
PAINT MONO (-210 3385);
FORCEPROP 0 LASTPIN (-200 3525) $PN AU56
J 2
(-210 3535);
DISPLAY 0.680851 (-210 3535);
PAINT MONO (-210 3535);
FORCEPROP 0 LASTPIN (-200 3575) $PN AU58
J 2
(-210 3585);
DISPLAY 0.680851 (-210 3585);
PAINT MONO (-210 3585);
FORCEPROP 0 LASTPIN (-200 3425) $PN AV32
J 2
(-210 3435);
DISPLAY 0.680851 (-210 3435);
PAINT MONO (-210 3435);
FORCEPROP 0 LASTPIN (2250 3525) $PN AV38
J 0
(2260 3535);
DISPLAY 0.680851 (2260 3535);
PAINT MONO (2260 3535);
FORCEPROP 0 LASTPIN (2250 3575) $PN AV40
J 0
(2260 3585);
DISPLAY 0.680851 (2260 3585);
PAINT MONO (2260 3585);
FORCEPROP 0 LASTPIN (2250 3275) $PN BC23
J 0
(2260 3285);
DISPLAY 0.680851 (2260 3285);
PAINT MONO (2260 3285);
FORCEPROP 0 LASTPIN (2250 3175) $PN BE23
J 0
(2260 3185);
DISPLAY 0.680851 (2260 3185);
PAINT MONO (2260 3185);
FORCEPROP 0 LASTPIN (2250 3225) $PN BF24
J 0
(2260 3235);
DISPLAY 0.680851 (2260 3235);
PAINT MONO (2260 3235);
FORCEPROP 0 LASTPIN (2250 2775) $PN CC64
J 0
(2260 2785);
DISPLAY 0.680851 (2260 2785);
PAINT MONO (2260 2785);
FORCEPROP 0 LASTPIN (2250 2825) $PN CE62
J 0
(2260 2835);
DISPLAY 0.680851 (2260 2835);
PAINT MONO (2260 2835);
FORCEPROP 0 LASTPIN (2250 2925) $PN CN60
J 0
(2260 2935);
DISPLAY 0.680851 (2260 2935);
PAINT MONO (2260 2935);
FORCEPROP 0 LASTPIN (2250 2725) $PN CP61
J 0
(2260 2735);
DISPLAY 0.680851 (2260 2735);
PAINT MONO (2260 2735);
FORCEPROP 0 LASTPIN (2250 2975) $PN CR60
J 0
(2260 2985);
DISPLAY 0.680851 (2260 2985);
PAINT MONO (2260 2985);
FORCEPROP 0 LASTPIN (2250 2875) $PN CU62
J 0
(2260 2885);
DISPLAY 0.680851 (2260 2885);
PAINT MONO (2260 2885);
FORCEPROP 0 LASTPIN (-200 3225) $PN CY38
J 2
(-210 3235);
DISPLAY 0.680851 (-210 3235);
PAINT MONO (-210 3235);
FORCEPROP 0 LASTPIN (-200 3075) $PN CY49
J 2
(-210 3085);
DISPLAY 0.680851 (-210 3085);
PAINT MONO (-210 3085);
FORCEPROP 0 LASTPIN (-200 3125) $PN DA45
J 2
(-210 3135);
DISPLAY 0.680851 (-210 3135);
PAINT MONO (-210 3135);
FORCEPROP 0 LASTPIN (2250 3425) $PN H12
J 0
(2260 3435);
DISPLAY 0.680851 (2260 3435);
PAINT MONO (2260 3435);
FORCEPROP 0 LASTPIN (-200 3275) $PN CY24
J 2
(-210 3285);
DISPLAY 0.680851 (-210 3285);
PAINT MONO (-210 3285);
FORCEPROP 0 LASTPIN (-200 2175) $PN AT85
J 2
(-210 2185);
DISPLAY 0.680851 (-210 2185);
PAINT MONO (-210 2185);
FORCEPROP 0 LASTPIN (-200 2325) $PN BN11
J 2
(-210 2335);
DISPLAY 0.680851 (-210 2335);
PAINT MONO (-210 2335);
FORCEPROP 2 LAST CDS_LIB pure_quanta
J 0
(1025 2875);
DISPLAY INVISIBLE (1025 2875);
FORCEPROP 1 LAST NEEDS_NO_SIZE TRUE
J 0
(1025 2875);
DISPLAY 0.723404 (1025 2875);
PAINT GREEN (1025 2875);
DISPLAY INVISIBLE (1025 2875);
FORCEPROP 1 LAST CDS_LMAN_SYM_OUTLINE -1100,850,1050,-850
J 0
(1025 2875);
DISPLAY 0.468085 (1025 2875);
PAINT GREEN (1025 2875);
DISPLAY INVISIBLE (1025 2875);
FORCEPROP 2 LAST CDS_LOCATION U2
J 0
(-75 4050);
DISPLAY 1.021277 (-75 4050);
DISPLAY INVISIBLE (-75 4050);
FORCEPROP 0 LAST $SEC 4
J 0
(-75 4050);
DISPLAY 0.680851 (-75 4050);
PAINT MONO (-75 4050);
DISPLAY INVISIBLE (-75 4050);
FORCEPROP 2 LAST CDS_SEC 4
J 0
(-75 4050);
DISPLAY 1.021277 (-75 4050);
DISPLAY INVISIBLE (-75 4050);
FORCEPROP 1 LAST PATH I1
J 0
(1025 2875);
DISPLAY 0.723404 (1025 2875);
PAINT GREEN (1025 2875);
DISPLAY INVISIBLE (1025 2875);
FORCEADD OFFPAGE..2
R 2
(-1925 2225);
FORCEPROP 2 LAST $XR0 266 
J 0
(-2210 2225);
DISPLAY 0.638298 (-2210 2225);
PAINT MONO (-2210 2225);
FORCEPROP 2 LAST CDS_LIB standard
J 0
(-1925 2225);
PAINT MONO (-1925 2225);
DISPLAY INVISIBLE (-1925 2225);
FORCEPROP 1 LAST OFFPAGE TRUE
J 2
(-2250 2100);
DISPLAY 0.872340 (-2250 2100);
DISPLAY INVISIBLE (-2250 2100);
FORCEPROP 1 LAST COMMENT_BODY TRUE
J 2
(-1880 2130);
DISPLAY 0.872340 (-1880 2130);
PAINT GREEN (-1880 2130);
DISPLAY INVISIBLE (-1880 2130);
FORCEPROP 2 LAST PATH I10
J 0
(-1875 2300);
DISPLAY 1.021277 (-1875 2300);
DISPLAY INVISIBLE (-1875 2300);
FORCEADD OFFPAGE..2
R 2
(-1925 2175);
FORCEPROP 2 LAST $XR0 266 
J 0
(-2210 2175);
DISPLAY 0.638298 (-2210 2175);
PAINT MONO (-2210 2175);
FORCEPROP 2 LAST CDS_LIB standard
J 0
(-1925 2175);
PAINT MONO (-1925 2175);
DISPLAY INVISIBLE (-1925 2175);
FORCEPROP 1 LAST OFFPAGE TRUE
J 2
(-2250 2050);
DISPLAY 0.872340 (-2250 2050);
DISPLAY INVISIBLE (-2250 2050);
FORCEPROP 1 LAST COMMENT_BODY TRUE
J 2
(-1880 2080);
DISPLAY 0.872340 (-1880 2080);
PAINT GREEN (-1880 2080);
DISPLAY INVISIBLE (-1880 2080);
FORCEPROP 2 LAST PATH I11
J 0
(-1875 2250);
DISPLAY 1.021277 (-1875 2250);
DISPLAY INVISIBLE (-1875 2250);
FORCEADD OFFPAGE..1
(-1925 2525);
FORCEPROP 2 LAST $XR0 117 
J 0
(-2177 2525);
DISPLAY 0.638298 (-2177 2525);
PAINT MONO (-2177 2525);
FORCEPROP 2 LAST CDS_LIB standard
J 0
(-1925 2525);
PAINT MONO (-1925 2525);
DISPLAY INVISIBLE (-1925 2525);
FORCEPROP 1 LAST OFFPAGE TRUE
J 0
(-1600 2400);
DISPLAY 0.872340 (-1600 2400);
DISPLAY INVISIBLE (-1600 2400);
FORCEPROP 1 LAST COMMENT_BODY TRUE
J 0
(-1800 2425);
DISPLAY 0.872340 (-1800 2425);
PAINT GREEN (-1800 2425);
DISPLAY INVISIBLE (-1800 2425);
FORCEPROP 2 LAST PATH I12
J 0
(-1875 2600);
DISPLAY 1.021277 (-1875 2600);
DISPLAY INVISIBLE (-1875 2600);
FORCEADD OFFPAGE..3
(3975 3075);
FORCEPROP 2 LAST $XR0 118 
J 0
(4189 3075);
DISPLAY 0.638298 (4189 3075);
PAINT MONO (4189 3075);
FORCEPROP 2 LAST CDS_LIB standard
J 0
(3975 3075);
PAINT MONO (3975 3075);
DISPLAY INVISIBLE (3975 3075);
FORCEPROP 1 LAST OFFPAGE TRUE
J 0
(4300 2950);
DISPLAY 1.170213 (4300 2950);
PAINT GREEN (4300 2950);
DISPLAY INVISIBLE (4300 2950);
FORCEPROP 1 LAST COMMENT_BODY TRUE
J 0
(3925 2975);
DISPLAY 1.170213 (3925 2975);
PAINT GREEN (3925 2975);
DISPLAY INVISIBLE (3925 2975);
FORCEPROP 2 LAST PATH I16
J 0
(4175 3150);
DISPLAY 1.021277 (4175 3150);
DISPLAY INVISIBLE (4175 3150);
FORCEADD OFFPAGE..3
(5525 2625);
FORCEPROP 2 LAST $XR1 16 
J 0
(5829 2625);
DISPLAY 0.638298 (5829 2625);
PAINT MONO (5829 2625);
FORCEPROP 2 LAST $XR0 47 
J 0
(5739 2625);
DISPLAY 0.638298 (5739 2625);
PAINT MONO (5739 2625);
FORCEPROP 2 LAST CDS_LIB standard
J 0
(5525 2625);
PAINT MONO (5525 2625);
DISPLAY INVISIBLE (5525 2625);
FORCEPROP 1 LAST OFFPAGE TRUE
J 0
(5850 2500);
DISPLAY 1.170213 (5850 2500);
PAINT GREEN (5850 2500);
DISPLAY INVISIBLE (5850 2500);
FORCEPROP 1 LAST COMMENT_BODY TRUE
J 0
(5475 2525);
DISPLAY 1.170213 (5475 2525);
PAINT GREEN (5475 2525);
DISPLAY INVISIBLE (5475 2525);
FORCEPROP 2 LAST PATH I18
J 0
(5725 2700);
DISPLAY 1.021277 (5725 2700);
DISPLAY INVISIBLE (5725 2700);
FORCEADD Q_RES..1
(3725 2625);
FORCEPROP 1 LAST PART_NUMBER CS11002FB07
J 0
(3850 2600);
DISPLAY 0.404255 (3850 2600);
DISPLAY INVISIBLE (3850 2600);
FORCEPROP 1 LAST MATERIAL CHIP
J 0
(4200 2600);
DISPLAY 0.404255 (4200 2600);
FORCEPROP 1 LAST TOLERANCE 1%
J 0
(3950 2625);
DISPLAY 0.510638 (3950 2625);
FORCEPROP 1 LAST VALUE 100
J 2
(3925 2625);
DISPLAY 0.510638 (3925 2625);
FORCEPROP 1 LAST PACK_TYPE 0402LF
J 0
(4050 2625);
DISPLAY 0.510638 (4050 2625);
FORCEPROP 1 LAST WATTAGE 1/16W
J 2
(4175 2600);
DISPLAY 0.404255 (4175 2600);
FORCEPROP 1 LAST $LOCATION R22
J 0
(3550 2625);
DISPLAY 0.638298 (3550 2625);
FORCEPROP 1 LASTPIN (3625 2625) $PN 1
J 0
(3637 2637);
DISPLAY 0.787234 (3637 2637);
FORCEPROP 1 LASTPIN (3825 2625) $PN 2
J 0
(3787 2637);
DISPLAY 0.787234 (3787 2637);
FORCEPROP 2 LAST CDS_LIB pure_quanta
J 0
(3725 2625);
PAINT MONO (3725 2625);
DISPLAY INVISIBLE (3725 2625);
FORCEPROP 1 LAST $LOCATION R22
J 0
(3675 2825);
DISPLAY 1.021277 (3675 2825);
DISPLAY INVISIBLE (3675 2825);
FORCEPROP 2 LAST CDS_LOCATION R22
J 0
(3675 2825);
DISPLAY 1.021277 (3675 2825);
DISPLAY INVISIBLE (3675 2825);
FORCEPROP 2 LAST $SEC 1
J 0
(3675 2825);
DISPLAY 0.680851 (3675 2825);
PAINT MONO (3675 2825);
DISPLAY INVISIBLE (3675 2825);
FORCEPROP 2 LAST CDS_SEC 1
J 0
(3675 2825);
DISPLAY 1.021277 (3675 2825);
DISPLAY INVISIBLE (3675 2825);
FORCEPROP 1 LAST PATH I19
J 0
(3675 2775);
DISPLAY 0.978723 (3675 2775);
PAINT WHITE (3675 2775);
DISPLAY INVISIBLE (3675 2775);
FORCEADD OFFPAGE..2
R 2
(-1925 2975);
FORCEPROP 2 LAST $XR0 274 
J 0
(-2210 2975);
DISPLAY 0.638298 (-2210 2975);
PAINT MONO (-2210 2975);
FORCEPROP 2 LAST CDS_LIB standard
J 0
(-1925 2975);
PAINT MONO (-1925 2975);
DISPLAY INVISIBLE (-1925 2975);
FORCEPROP 1 LAST OFFPAGE TRUE
J 2
(-2250 2850);
DISPLAY 0.872340 (-2250 2850);
DISPLAY INVISIBLE (-2250 2850);
FORCEPROP 1 LAST COMMENT_BODY TRUE
J 2
(-1880 2880);
DISPLAY 0.872340 (-1880 2880);
PAINT GREEN (-1880 2880);
DISPLAY INVISIBLE (-1880 2880);
FORCEPROP 2 LAST PATH I2
J 0
(-1875 3050);
DISPLAY 1.021277 (-1875 3050);
DISPLAY INVISIBLE (-1875 3050);
FORCEADD Q_RES..1
(3725 2575);
FORCEPROP 1 LAST PART_NUMBER CS11002FB07
J 0
(3850 2550);
DISPLAY 0.404255 (3850 2550);
DISPLAY INVISIBLE (3850 2550);
FORCEPROP 1 LAST MATERIAL CHIP
J 0
(4200 2550);
DISPLAY 0.404255 (4200 2550);
FORCEPROP 1 LAST TOLERANCE 1%
J 0
(3950 2575);
DISPLAY 0.510638 (3950 2575);
FORCEPROP 1 LAST VALUE 100
J 2
(3925 2575);
DISPLAY 0.510638 (3925 2575);
FORCEPROP 1 LAST PACK_TYPE 0402LF
J 0
(4050 2575);
DISPLAY 0.510638 (4050 2575);
FORCEPROP 1 LAST WATTAGE 1/16W
J 2
(4175 2550);
DISPLAY 0.404255 (4175 2550);
FORCEPROP 1 LAST $LOCATION R23
J 0
(3550 2575);
DISPLAY 0.638298 (3550 2575);
FORCEPROP 1 LASTPIN (3625 2575) $PN 1
J 0
(3637 2587);
DISPLAY 0.787234 (3637 2587);
FORCEPROP 1 LASTPIN (3825 2575) $PN 2
J 0
(3787 2587);
DISPLAY 0.787234 (3787 2587);
FORCEPROP 2 LAST CDS_LIB pure_quanta
J 0
(3725 2575);
PAINT MONO (3725 2575);
DISPLAY INVISIBLE (3725 2575);
FORCEPROP 1 LAST $LOCATION R23
J 0
(3675 2775);
DISPLAY 1.021277 (3675 2775);
DISPLAY INVISIBLE (3675 2775);
FORCEPROP 2 LAST CDS_LOCATION R23
J 0
(3675 2775);
DISPLAY 1.021277 (3675 2775);
DISPLAY INVISIBLE (3675 2775);
FORCEPROP 2 LAST $SEC 1
J 0
(3675 2775);
DISPLAY 0.680851 (3675 2775);
PAINT MONO (3675 2775);
DISPLAY INVISIBLE (3675 2775);
FORCEPROP 2 LAST CDS_SEC 1
J 0
(3675 2775);
DISPLAY 1.021277 (3675 2775);
DISPLAY INVISIBLE (3675 2775);
FORCEPROP 1 LAST PATH I20
J 0
(3675 2725);
DISPLAY 0.978723 (3675 2725);
PAINT WHITE (3675 2725);
DISPLAY INVISIBLE (3675 2725);
FORCEADD OFFPAGE..3
(5525 2575);
FORCEPROP 2 LAST $XR1 16 
J 0
(5829 2575);
DISPLAY 0.638298 (5829 2575);
PAINT MONO (5829 2575);
FORCEPROP 2 LAST $XR0 47 
J 0
(5739 2575);
DISPLAY 0.638298 (5739 2575);
PAINT MONO (5739 2575);
FORCEPROP 2 LAST CDS_LIB standard
J 0
(5525 2575);
PAINT MONO (5525 2575);
DISPLAY INVISIBLE (5525 2575);
FORCEPROP 1 LAST OFFPAGE TRUE
J 0
(5850 2450);
DISPLAY 1.170213 (5850 2450);
PAINT GREEN (5850 2450);
DISPLAY INVISIBLE (5850 2450);
FORCEPROP 1 LAST COMMENT_BODY TRUE
J 0
(5475 2475);
DISPLAY 1.170213 (5475 2475);
PAINT GREEN (5475 2475);
DISPLAY INVISIBLE (5475 2475);
FORCEPROP 2 LAST PATH I21
J 0
(5725 2650);
DISPLAY 1.021277 (5725 2650);
DISPLAY INVISIBLE (5725 2650);
FORCEADD OFFPAGE..3
(5525 2525);
FORCEPROP 2 LAST $XR1 132 
J 0
(5829 2525);
DISPLAY 0.638298 (5829 2525);
PAINT MONO (5829 2525);
FORCEPROP 2 LAST $XR0 47 
J 0
(5739 2525);
DISPLAY 0.638298 (5739 2525);
PAINT MONO (5739 2525);
FORCEPROP 2 LAST CDS_LIB standard
J 0
(5525 2525);
PAINT MONO (5525 2525);
DISPLAY INVISIBLE (5525 2525);
FORCEPROP 1 LAST OFFPAGE TRUE
J 0
(5850 2400);
DISPLAY 1.170213 (5850 2400);
PAINT GREEN (5850 2400);
DISPLAY INVISIBLE (5850 2400);
FORCEPROP 1 LAST COMMENT_BODY TRUE
J 0
(5475 2425);
DISPLAY 1.170213 (5475 2425);
PAINT GREEN (5475 2425);
DISPLAY INVISIBLE (5475 2425);
FORCEPROP 2 LAST PATH I23
J 0
(5725 2600);
DISPLAY 1.021277 (5725 2600);
DISPLAY INVISIBLE (5725 2600);
FORCEADD OFFPAGE..3
(5525 2475);
FORCEPROP 2 LAST $XR1 132 
J 0
(5829 2475);
DISPLAY 0.638298 (5829 2475);
PAINT MONO (5829 2475);
FORCEPROP 2 LAST $XR0 47 
J 0
(5739 2475);
DISPLAY 0.638298 (5739 2475);
PAINT MONO (5739 2475);
FORCEPROP 2 LAST CDS_LIB standard
J 0
(5525 2475);
PAINT MONO (5525 2475);
DISPLAY INVISIBLE (5525 2475);
FORCEPROP 1 LAST OFFPAGE TRUE
J 0
(5850 2350);
DISPLAY 1.170213 (5850 2350);
PAINT GREEN (5850 2350);
DISPLAY INVISIBLE (5850 2350);
FORCEPROP 1 LAST COMMENT_BODY TRUE
J 0
(5475 2375);
DISPLAY 1.170213 (5475 2375);
PAINT GREEN (5475 2375);
DISPLAY INVISIBLE (5475 2375);
FORCEPROP 2 LAST PATH I24
J 0
(5725 2550);
DISPLAY 1.021277 (5725 2550);
DISPLAY INVISIBLE (5725 2550);
FORCEADD Q_RES..1
(3725 2525);
FORCEPROP 1 LAST PART_NUMBER CS01002FB07
J 0
(3850 2550);
DISPLAY 0.404255 (3850 2550);
DISPLAY INVISIBLE (3850 2550);
FORCEPROP 1 LAST TOLERANCE 1%
J 0
(3950 2525);
DISPLAY 0.510638 (3950 2525);
FORCEPROP 1 LAST MATERIAL CHIP
J 0
(4200 2550);
DISPLAY 0.404255 (4200 2550);
FORCEPROP 1 LAST VALUE 10
J 2
(3900 2525);
DISPLAY 0.510638 (3900 2525);
FORCEPROP 1 LAST PACK_TYPE 0402LF
J 0
(4050 2525);
DISPLAY 0.510638 (4050 2525);
FORCEPROP 1 LAST WATTAGE 1/16W
J 2
(4175 2550);
DISPLAY 0.404255 (4175 2550);
FORCEPROP 1 LAST $LOCATION R24
J 0
(3550 2525);
DISPLAY 0.638298 (3550 2525);
FORCEPROP 1 LASTPIN (3625 2525) $PN 1
J 0
(3637 2537);
DISPLAY 0.787234 (3637 2537);
FORCEPROP 1 LASTPIN (3825 2525) $PN 2
J 0
(3787 2537);
DISPLAY 0.787234 (3787 2537);
FORCEPROP 2 LAST CDS_LIB pure_quanta
J 0
(3725 2525);
PAINT MONO (3725 2525);
DISPLAY INVISIBLE (3725 2525);
FORCEPROP 1 LAST $LOCATION R24
J 0
(3675 2725);
DISPLAY 1.021277 (3675 2725);
DISPLAY INVISIBLE (3675 2725);
FORCEPROP 2 LAST CDS_LOCATION R24
J 0
(3675 2725);
DISPLAY 1.021277 (3675 2725);
DISPLAY INVISIBLE (3675 2725);
FORCEPROP 2 LAST $SEC 1
J 0
(3675 2725);
DISPLAY 0.680851 (3675 2725);
PAINT MONO (3675 2725);
DISPLAY INVISIBLE (3675 2725);
FORCEPROP 2 LAST CDS_SEC 1
J 0
(3675 2725);
DISPLAY 1.021277 (3675 2725);
DISPLAY INVISIBLE (3675 2725);
FORCEPROP 1 LAST PATH I25
J 0
(3675 2675);
DISPLAY 0.978723 (3675 2675);
PAINT WHITE (3675 2675);
DISPLAY INVISIBLE (3675 2675);
FORCEADD Q_RES..1
(3725 2475);
FORCEPROP 1 LAST PART_NUMBER CS01002FB07
J 0
(3850 2500);
DISPLAY 0.404255 (3850 2500);
DISPLAY INVISIBLE (3850 2500);
FORCEPROP 1 LAST VALUE 10
J 2
(3900 2475);
DISPLAY 0.510638 (3900 2475);
FORCEPROP 1 LAST MATERIAL CHIP
J 0
(4200 2500);
DISPLAY 0.404255 (4200 2500);
FORCEPROP 1 LAST TOLERANCE 1%
J 0
(3950 2475);
DISPLAY 0.510638 (3950 2475);
FORCEPROP 1 LAST PACK_TYPE 0402LF
J 0
(4050 2475);
DISPLAY 0.510638 (4050 2475);
FORCEPROP 1 LAST WATTAGE 1/16W
J 2
(4175 2500);
DISPLAY 0.404255 (4175 2500);
FORCEPROP 1 LAST $LOCATION R25
J 0
(3550 2475);
DISPLAY 0.638298 (3550 2475);
FORCEPROP 1 LASTPIN (3625 2475) $PN 1
J 0
(3637 2487);
DISPLAY 0.787234 (3637 2487);
FORCEPROP 1 LASTPIN (3825 2475) $PN 2
J 0
(3787 2487);
DISPLAY 0.787234 (3787 2487);
FORCEPROP 2 LAST CDS_LIB pure_quanta
J 0
(3725 2475);
PAINT MONO (3725 2475);
DISPLAY INVISIBLE (3725 2475);
FORCEPROP 1 LAST $LOCATION R25
J 0
(3675 2675);
DISPLAY 1.021277 (3675 2675);
DISPLAY INVISIBLE (3675 2675);
FORCEPROP 2 LAST CDS_LOCATION R25
J 0
(3675 2675);
DISPLAY 1.021277 (3675 2675);
DISPLAY INVISIBLE (3675 2675);
FORCEPROP 2 LAST $SEC 1
J 0
(3675 2675);
DISPLAY 0.680851 (3675 2675);
PAINT MONO (3675 2675);
DISPLAY INVISIBLE (3675 2675);
FORCEPROP 2 LAST CDS_SEC 1
J 0
(3675 2675);
DISPLAY 1.021277 (3675 2675);
DISPLAY INVISIBLE (3675 2675);
FORCEPROP 1 LAST PATH I26
J 0
(3675 2625);
DISPLAY 0.978723 (3675 2625);
PAINT WHITE (3675 2625);
DISPLAY INVISIBLE (3675 2625);
FORCEADD UNIVERSAL_POWER..1
(2700 2075);
FORCEPROP 3 LASTPIN (2700 2025) SIG_NAME PVNN_TERM_CPU0\g
J 0
(2710 2035);
DISPLAY 0.659574 (2710 2035);
PAINT MONO (2710 2035);
DISPLAY INVISIBLE (2710 2035);
FORCEPROP 1 LAST HDL_POWER PVNN_TERM_CPU0
J 1
(2700 2125);
DISPLAY 0.872340 (2700 2125);
PAINT GREEN (2700 2125);
FORCEPROP 2 LAST CDS_LIB logical_power
J 0
(2700 2075);
PAINT MONO (2700 2075);
DISPLAY INVISIBLE (2700 2075);
FORCEPROP 1 LAST PATH I28
J 0
(2750 2100);
DISPLAY 0.872340 (2750 2100);
PAINT AQUA (2750 2100);
DISPLAY INVISIBLE (2750 2100);
FORCEADD OFFPAGE..1
(2500 1375);
FORCEPROP 2 LAST $XR1 47 
J 0
(2159 1375);
DISPLAY 0.638298 (2159 1375);
PAINT MONO (2159 1375);
FORCEPROP 2 LAST $XR0 16 
J 0
(2249 1375);
DISPLAY 0.638298 (2249 1375);
PAINT MONO (2249 1375);
FORCEPROP 2 LAST CDS_LIB standard
J 0
(2500 1375);
PAINT MONO (2500 1375);
DISPLAY INVISIBLE (2500 1375);
FORCEPROP 1 LAST OFFPAGE TRUE
J 0
(2825 1250);
DISPLAY 0.872340 (2825 1250);
DISPLAY INVISIBLE (2825 1250);
FORCEPROP 1 LAST COMMENT_BODY TRUE
J 0
(2625 1275);
DISPLAY 0.872340 (2625 1275);
PAINT GREEN (2625 1275);
DISPLAY INVISIBLE (2625 1275);
FORCEPROP 2 LAST PATH I29
J 0
(2550 1450);
DISPLAY 1.021277 (2550 1450);
DISPLAY INVISIBLE (2550 1450);
FORCEADD OFFPAGE..2
R 2
(-1925 2925);
FORCEPROP 2 LAST $XR0 274 
J 0
(-2210 2925);
DISPLAY 0.638298 (-2210 2925);
PAINT MONO (-2210 2925);
FORCEPROP 2 LAST CDS_LIB standard
J 0
(-1925 2925);
PAINT MONO (-1925 2925);
DISPLAY INVISIBLE (-1925 2925);
FORCEPROP 1 LAST OFFPAGE TRUE
J 2
(-2250 2800);
DISPLAY 0.872340 (-2250 2800);
DISPLAY INVISIBLE (-2250 2800);
FORCEPROP 1 LAST COMMENT_BODY TRUE
J 2
(-1880 2830);
DISPLAY 0.872340 (-1880 2830);
PAINT GREEN (-1880 2830);
DISPLAY INVISIBLE (-1880 2830);
FORCEPROP 2 LAST PATH I3
J 0
(-1875 3000);
DISPLAY 1.021277 (-1875 3000);
DISPLAY INVISIBLE (-1875 3000);
FORCEADD OFFPAGE..1
(2500 1325);
FORCEPROP 2 LAST $XR1 47 
J 0
(2159 1325);
DISPLAY 0.638298 (2159 1325);
PAINT MONO (2159 1325);
FORCEPROP 2 LAST $XR0 16 
J 0
(2249 1325);
DISPLAY 0.638298 (2249 1325);
PAINT MONO (2249 1325);
FORCEPROP 2 LAST CDS_LIB standard
J 0
(2500 1325);
PAINT MONO (2500 1325);
DISPLAY INVISIBLE (2500 1325);
FORCEPROP 1 LAST OFFPAGE TRUE
J 0
(2825 1200);
DISPLAY 0.872340 (2825 1200);
DISPLAY INVISIBLE (2825 1200);
FORCEPROP 1 LAST COMMENT_BODY TRUE
J 0
(2625 1225);
DISPLAY 0.872340 (2625 1225);
PAINT GREEN (2625 1225);
DISPLAY INVISIBLE (2625 1225);
FORCEPROP 2 LAST PATH I30
J 0
(2550 1400);
DISPLAY 1.021277 (2550 1400);
DISPLAY INVISIBLE (2550 1400);
FORCEADD Q_RES..1
(4125 1375);
FORCEPROP 1 LAST PART_NUMBER CS00002JB13
J 0
(4275 1350);
DISPLAY 0.404255 (4275 1350);
DISPLAY INVISIBLE (4275 1350);
FORCEPROP 1 LAST PACK_TYPE 0402LF
J 0
(4450 1375);
DISPLAY 0.510638 (4450 1375);
FORCEPROP 1 LAST VALUE 0
J 2
(4325 1375);
DISPLAY 0.510638 (4325 1375);
FORCEPROP 1 LAST TOLERANCE 5%
J 0
(4350 1375);
DISPLAY 0.510638 (4350 1375);
FORCEPROP 1 LAST WATTAGE 1/16W
J 2
(4700 1350);
DISPLAY 0.404255 (4700 1350);
FORCEPROP 1 LAST MATERIAL CHIP
J 0
(4500 1350);
DISPLAY 0.404255 (4500 1350);
FORCEPROP 1 LAST $LOCATION R20
J 0
(3950 1375);
DISPLAY 0.787234 (3950 1375);
FORCEPROP 1 LASTPIN (4025 1375) $PN 1
J 0
(4037 1387);
DISPLAY 0.787234 (4037 1387);
FORCEPROP 1 LASTPIN (4225 1375) $PN 2
J 0
(4187 1387);
DISPLAY 0.787234 (4187 1387);
FORCEPROP 2 LAST CDS_LIB pure_quanta
J 0
(4125 1375);
PAINT MONO (4125 1375);
DISPLAY INVISIBLE (4125 1375);
FORCEPROP 1 LAST $LOCATION R20
J 0
(4075 1575);
DISPLAY 1.021277 (4075 1575);
DISPLAY INVISIBLE (4075 1575);
FORCEPROP 2 LAST CDS_LOCATION R20
J 0
(4075 1575);
DISPLAY 1.021277 (4075 1575);
DISPLAY INVISIBLE (4075 1575);
FORCEPROP 2 LAST $SEC 1
J 0
(4075 1575);
DISPLAY 0.680851 (4075 1575);
PAINT MONO (4075 1575);
DISPLAY INVISIBLE (4075 1575);
FORCEPROP 2 LAST CDS_SEC 1
J 0
(4075 1575);
DISPLAY 1.021277 (4075 1575);
DISPLAY INVISIBLE (4075 1575);
FORCEPROP 1 LAST PATH I31
J 0
(4075 1525);
DISPLAY 0.978723 (4075 1525);
PAINT WHITE (4075 1525);
DISPLAY INVISIBLE (4075 1525);
FORCEADD Q_RES..1
(4125 1325);
FORCEPROP 1 LAST PART_NUMBER CS00002JB13
J 0
(4275 1300);
DISPLAY 0.404255 (4275 1300);
DISPLAY INVISIBLE (4275 1300);
FORCEPROP 1 LAST MATERIAL CHIP
J 0
(4500 1300);
DISPLAY 0.404255 (4500 1300);
FORCEPROP 1 LAST TOLERANCE 5%
J 0
(4350 1325);
DISPLAY 0.510638 (4350 1325);
FORCEPROP 1 LAST VALUE 0
J 2
(4325 1325);
DISPLAY 0.510638 (4325 1325);
FORCEPROP 1 LAST PACK_TYPE 0402LF
J 0
(4450 1325);
DISPLAY 0.510638 (4450 1325);
FORCEPROP 1 LAST WATTAGE 1/16W
J 2
(4700 1300);
DISPLAY 0.404255 (4700 1300);
FORCEPROP 1 LAST $LOCATION R21
J 0
(3950 1325);
DISPLAY 0.787234 (3950 1325);
FORCEPROP 1 LASTPIN (4025 1325) $PN 1
J 0
(4037 1337);
DISPLAY 0.787234 (4037 1337);
FORCEPROP 1 LASTPIN (4225 1325) $PN 2
J 0
(4187 1337);
DISPLAY 0.787234 (4187 1337);
FORCEPROP 2 LAST CDS_LIB pure_quanta
J 0
(4125 1325);
PAINT MONO (4125 1325);
DISPLAY INVISIBLE (4125 1325);
FORCEPROP 1 LAST $LOCATION R21
J 0
(4075 1525);
DISPLAY 1.021277 (4075 1525);
DISPLAY INVISIBLE (4075 1525);
FORCEPROP 2 LAST CDS_LOCATION R21
J 0
(4075 1525);
DISPLAY 1.021277 (4075 1525);
DISPLAY INVISIBLE (4075 1525);
FORCEPROP 2 LAST $SEC 1
J 0
(4075 1525);
DISPLAY 0.680851 (4075 1525);
PAINT MONO (4075 1525);
DISPLAY INVISIBLE (4075 1525);
FORCEPROP 2 LAST CDS_SEC 1
J 0
(4075 1525);
DISPLAY 1.021277 (4075 1525);
DISPLAY INVISIBLE (4075 1525);
FORCEPROP 1 LAST PATH I32
J 0
(4075 1475);
DISPLAY 0.978723 (4075 1475);
PAINT WHITE (4075 1475);
DISPLAY INVISIBLE (4075 1475);
FORCEADD OFFPAGE..3
(5525 1375);
FORCEPROP 2 LAST $XR0 182 
J 0
(5739 1375);
DISPLAY 0.638298 (5739 1375);
PAINT MONO (5739 1375);
FORCEPROP 2 LAST CDS_LIB standard
J 0
(5525 1375);
PAINT MONO (5525 1375);
DISPLAY INVISIBLE (5525 1375);
FORCEPROP 1 LAST OFFPAGE TRUE
J 0
(5850 1250);
DISPLAY 1.170213 (5850 1250);
PAINT GREEN (5850 1250);
DISPLAY INVISIBLE (5850 1250);
FORCEPROP 1 LAST COMMENT_BODY TRUE
J 0
(5475 1275);
DISPLAY 1.170213 (5475 1275);
PAINT GREEN (5475 1275);
DISPLAY INVISIBLE (5475 1275);
FORCEPROP 2 LAST PATH I33
J 0
(5725 1450);
DISPLAY 1.021277 (5725 1450);
DISPLAY INVISIBLE (5725 1450);
FORCEADD OFFPAGE..3
(5525 1325);
FORCEPROP 2 LAST $XR0 182 
J 0
(5739 1325);
DISPLAY 0.638298 (5739 1325);
PAINT MONO (5739 1325);
FORCEPROP 2 LAST CDS_LIB standard
J 0
(5525 1325);
PAINT MONO (5525 1325);
DISPLAY INVISIBLE (5525 1325);
FORCEPROP 1 LAST OFFPAGE TRUE
J 0
(5850 1200);
DISPLAY 1.170213 (5850 1200);
PAINT GREEN (5850 1200);
DISPLAY INVISIBLE (5850 1200);
FORCEPROP 1 LAST COMMENT_BODY TRUE
J 0
(5475 1225);
DISPLAY 1.170213 (5475 1225);
PAINT GREEN (5475 1225);
DISPLAY INVISIBLE (5475 1225);
FORCEPROP 2 LAST PATH I34
J 0
(5725 1400);
DISPLAY 1.021277 (5725 1400);
DISPLAY INVISIBLE (5725 1400);
FORCEADD Q_RES..2
(2700 1750);
FORCEPROP 1 LAST PART_NUMBER CS14992FB06
J 0
(2740 1625);
DISPLAY 0.638298 (2740 1625);
DISPLAY INVISIBLE (2740 1625);
FORCEPROP 1 LAST WATTAGE 1/16W
J 0
(2740 1725);
DISPLAY 0.638298 (2740 1725);
FORCEPROP 1 LAST VALUE 499
J 0
(2745 1825);
DISPLAY 0.638298 (2745 1825);
FORCEPROP 1 LAST PACK_TYPE 0402LF
J 0
(2740 1575);
DISPLAY 0.638298 (2740 1575);
FORCEPROP 1 LAST TOLERANCE 1%
J 0
(2745 1775);
DISPLAY 0.638298 (2745 1775);
FORCEPROP 1 LAST MATERIAL CHIP
J 0
(2740 1675);
DISPLAY 0.638298 (2740 1675);
FORCEPROP 1 LASTPIN (2700 1850) $PN 1
J 0
(2705 1812);
DISPLAY 0.787234 (2705 1812);
FORCEPROP 1 LASTPIN (2700 1650) $PN 2
J 0
(2705 1660);
DISPLAY 0.787234 (2705 1660);
FORCEPROP 1 LAST $LOCATION R18
J 0
(2745 1875);
DISPLAY 0.978723 (2745 1875);
FORCEPROP 2 LAST CDS_LIB pure_quanta
J 0
(2700 1750);
PAINT MONO (2700 1750);
DISPLAY INVISIBLE (2700 1750);
FORCEPROP 1 LAST $LOCATION R18
J 0
(2750 1975);
DISPLAY 1.021277 (2750 1975);
DISPLAY INVISIBLE (2750 1975);
FORCEPROP 2 LAST CDS_LOCATION R18
J 0
(2750 1975);
DISPLAY 1.021277 (2750 1975);
DISPLAY INVISIBLE (2750 1975);
FORCEPROP 2 LAST $SEC 1
J 0
(2750 1975);
DISPLAY 0.680851 (2750 1975);
PAINT MONO (2750 1975);
DISPLAY INVISIBLE (2750 1975);
FORCEPROP 2 LAST CDS_SEC 1
J 0
(2750 1975);
DISPLAY 1.021277 (2750 1975);
DISPLAY INVISIBLE (2750 1975);
FORCEPROP 1 LAST PATH I35
J 0
(2750 1925);
DISPLAY 0.978723 (2750 1925);
PAINT WHITE (2750 1925);
DISPLAY INVISIBLE (2750 1925);
FORCEADD Q_RES..2
(3075 1750);
FORCEPROP 1 LAST PART_NUMBER CS14992FB06
J 0
(3115 1625);
DISPLAY 0.638298 (3115 1625);
DISPLAY INVISIBLE (3115 1625);
FORCEPROP 1 LAST TOLERANCE 1%
J 0
(3120 1775);
DISPLAY 0.638298 (3120 1775);
FORCEPROP 1 LAST PACK_TYPE 0402LF
J 0
(3115 1575);
DISPLAY 0.638298 (3115 1575);
FORCEPROP 1 LAST VALUE 499
J 0
(3120 1825);
DISPLAY 0.638298 (3120 1825);
FORCEPROP 1 LAST MATERIAL CHIP
J 0
(3115 1675);
DISPLAY 0.638298 (3115 1675);
FORCEPROP 1 LAST WATTAGE 1/16W
J 0
(3115 1725);
DISPLAY 0.638298 (3115 1725);
FORCEPROP 1 LAST $LOCATION R19
J 0
(3120 1875);
DISPLAY 0.978723 (3120 1875);
FORCEPROP 1 LASTPIN (3075 1850) $PN 1
J 0
(3080 1812);
DISPLAY 0.787234 (3080 1812);
FORCEPROP 1 LASTPIN (3075 1650) $PN 2
J 0
(3080 1660);
DISPLAY 0.787234 (3080 1660);
FORCEPROP 2 LAST CDS_LIB pure_quanta
J 0
(3075 1750);
PAINT MONO (3075 1750);
DISPLAY INVISIBLE (3075 1750);
FORCEPROP 1 LAST $LOCATION R19
J 0
(3125 1975);
DISPLAY 1.021277 (3125 1975);
DISPLAY INVISIBLE (3125 1975);
FORCEPROP 2 LAST CDS_LOCATION R19
J 0
(3125 1975);
DISPLAY 1.021277 (3125 1975);
DISPLAY INVISIBLE (3125 1975);
FORCEPROP 2 LAST $SEC 1
J 0
(3125 1975);
DISPLAY 0.680851 (3125 1975);
PAINT MONO (3125 1975);
DISPLAY INVISIBLE (3125 1975);
FORCEPROP 2 LAST CDS_SEC 1
J 0
(3125 1975);
DISPLAY 1.021277 (3125 1975);
DISPLAY INVISIBLE (3125 1975);
FORCEPROP 1 LAST PATH I36
J 0
(3125 1925);
DISPLAY 0.978723 (3125 1925);
PAINT WHITE (3125 1925);
DISPLAY INVISIBLE (3125 1925);
FORCEADD OFFPAGE..2
R 2
(-1925 2825);
FORCEPROP 2 LAST $XR0 266 
J 0
(-2210 2825);
DISPLAY 0.638298 (-2210 2825);
PAINT MONO (-2210 2825);
FORCEPROP 2 LAST CDS_LIB standard
J 0
(-1925 2825);
PAINT MONO (-1925 2825);
DISPLAY INVISIBLE (-1925 2825);
FORCEPROP 1 LAST OFFPAGE TRUE
J 2
(-2250 2700);
DISPLAY 0.872340 (-2250 2700);
DISPLAY INVISIBLE (-2250 2700);
FORCEPROP 1 LAST COMMENT_BODY TRUE
J 2
(-1880 2730);
DISPLAY 0.872340 (-1880 2730);
PAINT GREEN (-1880 2730);
DISPLAY INVISIBLE (-1880 2730);
FORCEPROP 2 LAST PATH I4
J 0
(-1875 2900);
DISPLAY 1.021277 (-1875 2900);
DISPLAY INVISIBLE (-1875 2900);
FORCEADD OFFPAGE..2
R 2
(-1925 2775);
FORCEPROP 2 LAST $XR0 266 
J 0
(-2210 2775);
DISPLAY 0.638298 (-2210 2775);
PAINT MONO (-2210 2775);
FORCEPROP 2 LAST CDS_LIB standard
J 0
(-1925 2775);
PAINT MONO (-1925 2775);
DISPLAY INVISIBLE (-1925 2775);
FORCEPROP 1 LAST OFFPAGE TRUE
J 2
(-2250 2650);
DISPLAY 0.872340 (-2250 2650);
DISPLAY INVISIBLE (-2250 2650);
FORCEPROP 1 LAST COMMENT_BODY TRUE
J 2
(-1880 2680);
DISPLAY 0.872340 (-1880 2680);
PAINT GREEN (-1880 2680);
DISPLAY INVISIBLE (-1880 2680);
FORCEPROP 2 LAST PATH I5
J 0
(-1875 2850);
DISPLAY 1.021277 (-1875 2850);
DISPLAY INVISIBLE (-1875 2850);
FORCEADD OFFPAGE..2
R 2
(-1925 2675);
FORCEPROP 2 LAST $XR0 274 
J 0
(-2210 2675);
DISPLAY 0.638298 (-2210 2675);
PAINT MONO (-2210 2675);
FORCEPROP 2 LAST CDS_LIB standard
J 0
(-1925 2675);
PAINT MONO (-1925 2675);
DISPLAY INVISIBLE (-1925 2675);
FORCEPROP 1 LAST OFFPAGE TRUE
J 2
(-2250 2550);
DISPLAY 0.872340 (-2250 2550);
DISPLAY INVISIBLE (-2250 2550);
FORCEPROP 1 LAST COMMENT_BODY TRUE
J 2
(-1880 2580);
DISPLAY 0.872340 (-1880 2580);
PAINT GREEN (-1880 2580);
DISPLAY INVISIBLE (-1880 2580);
FORCEPROP 2 LAST PATH I6
J 0
(-1875 2750);
DISPLAY 1.021277 (-1875 2750);
DISPLAY INVISIBLE (-1875 2750);
FORCEADD OFFPAGE..2
R 2
(-1925 2625);
FORCEPROP 2 LAST $XR0 274 
J 0
(-2210 2625);
DISPLAY 0.638298 (-2210 2625);
PAINT MONO (-2210 2625);
FORCEPROP 2 LAST CDS_LIB standard
J 0
(-1925 2625);
PAINT MONO (-1925 2625);
DISPLAY INVISIBLE (-1925 2625);
FORCEPROP 1 LAST OFFPAGE TRUE
J 2
(-2250 2500);
DISPLAY 0.872340 (-2250 2500);
DISPLAY INVISIBLE (-2250 2500);
FORCEPROP 1 LAST COMMENT_BODY TRUE
J 2
(-1880 2530);
DISPLAY 0.872340 (-1880 2530);
PAINT GREEN (-1880 2530);
DISPLAY INVISIBLE (-1880 2530);
FORCEPROP 2 LAST PATH I7
J 0
(-1875 2700);
DISPLAY 1.021277 (-1875 2700);
DISPLAY INVISIBLE (-1875 2700);
FORCEADD OFFPAGE..2
R 2
(-1925 2325);
FORCEPROP 2 LAST $XR0 278 
J 0
(-2210 2325);
DISPLAY 0.638298 (-2210 2325);
PAINT MONO (-2210 2325);
FORCEPROP 2 LAST CDS_LIB standard
J 0
(-1925 2325);
PAINT MONO (-1925 2325);
DISPLAY INVISIBLE (-1925 2325);
FORCEPROP 1 LAST OFFPAGE TRUE
J 2
(-2250 2200);
DISPLAY 0.872340 (-2250 2200);
DISPLAY INVISIBLE (-2250 2200);
FORCEPROP 1 LAST COMMENT_BODY TRUE
J 2
(-1880 2230);
DISPLAY 0.872340 (-1880 2230);
PAINT GREEN (-1880 2230);
DISPLAY INVISIBLE (-1880 2230);
FORCEPROP 2 LAST PATH I8
J 0
(-1875 2400);
DISPLAY 1.021277 (-1875 2400);
DISPLAY INVISIBLE (-1875 2400);
FORCEADD OFFPAGE..2
R 2
(-1925 2375);
FORCEPROP 2 LAST $XR0 278 
J 0
(-2210 2375);
DISPLAY 0.638298 (-2210 2375);
PAINT MONO (-2210 2375);
FORCEPROP 2 LAST CDS_LIB standard
J 0
(-1925 2375);
PAINT MONO (-1925 2375);
DISPLAY INVISIBLE (-1925 2375);
FORCEPROP 1 LAST OFFPAGE TRUE
J 2
(-2250 2250);
DISPLAY 0.872340 (-2250 2250);
DISPLAY INVISIBLE (-2250 2250);
FORCEPROP 1 LAST COMMENT_BODY TRUE
J 2
(-1880 2280);
DISPLAY 0.872340 (-1880 2280);
PAINT GREEN (-1880 2280);
DISPLAY INVISIBLE (-1880 2280);
FORCEPROP 2 LAST PATH I9
J 0
(-1875 2450);
DISPLAY 1.021277 (-1875 2450);
DISPLAY INVISIBLE (-1875 2450);
FORCEADD QUANTA_TITLE_BLOCK_C..1
(6725 -1650);
FORCEPROP 0 LAST CDS_CON_LAST_MODIFIED Fri Aug 25 14:00:03 2023
J 0
(4840 -1635);
PAINT MONO (4840 -1635);
DISPLAY INVISIBLE (4840 -1635);
FORCEPROP 2 LAST CUSTOM_TXT_CDS <XR_PAGE_TITLE>
J 0
(-1165 3600);
DISPLAY 0.638298 (-1165 3600);
PAINT PINK (-1165 3600);
DISPLAY INVISIBLE (-1165 3600);
FORCEPROP 2 LAST CUSTOM_TXT_CDS <CON_LAST_MODIFIED>
J 0
(4840 -1635);
DISPLAY 0.978723 (4840 -1635);
FORCEPROP 2 LAST CUSTOM_TXT_CDS <Q_PROJ>
J 0
(4343 -1548);
DISPLAY 1.212766 (4343 -1548);
FORCEPROP 2 LAST CUSTOM_TXT_CDS <CON_PAGE_NUM> OF <CON_TOTAL_PAGES>
J 0
(6279 -1632);
DISPLAY 0.978723 (6279 -1632);
FORCEPROP 2 LAST CUSTOM_TXT_CDS <Q_REV>
J 0
(6541 -1547);
DISPLAY 1.212766 (6541 -1547);
FORCEPROP 2 LAST CUSTOM_TXT_CDS <Q_NUMBER>
J 0
(5322 -1547);
DISPLAY 1.212766 (5322 -1547);
FORCEPROP 1 LAST CUSTOM_TXT_CDS <NAME_2>
J 0
(3550 -1600);
FORCEPROP 1 LAST CUSTOM_TXT_CDS <NAME_1>
J 0
(3550 -1475);
FORCEPROP 1 LAST Q_TITLE SPR CPU0 MISC:DDRVIEW & VSENSE(4/30)
J 0
(-2641 -1624);
DISPLAY 1.957447 (-2641 -1624);
PAINT GREEN (-2641 -1624);
FORCEPROP 1 LAST Q_DEPT 
J 1
(2962 -1601);
DISPLAY 1.957447 (2962 -1601);
PAINT GREEN (2962 -1601);
FORCEPROP 2 LAST CDS_LIB pure_quanta
J 0
(6725 -1650);
PAINT MONO (6725 -1650);
DISPLAY INVISIBLE (6725 -1650);
FORCEPROP 1 LAST CDS_LMAN_SYM_OUTLINE -9475,6775,100,-125
J 0
(6725 -1650);
DISPLAY 0.468085 (6725 -1650);
PAINT GREEN (6725 -1650);
DISPLAY INVISIBLE (6725 -1650);
FORCEPROP 2 LAST PAGE_BORDER TRUE
J 0
(-1165 3600);
DISPLAY 0.638298 (-1165 3600);
PAINT PINK (-1165 3600);
DISPLAY INVISIBLE (-1165 3600);
FORCEPROP 2 LAST CDS_XR_PAGE_TITLE CR-16 : @S9S_MB_2U_LIB.S9S_MB_2U(SCH_1):PAGE16
J 0
(-1165 3600);
DISPLAY 0.638298 (-1165 3600);
PAINT PINK (-1165 3600);
DISPLAY INVISIBLE (-1165 3600);
FORCEPROP 1 LAST COMMENT_BODY TRUE
J 0
(6737 -1663);
DISPLAY 0.978723 (6737 -1663);
PAINT GREEN (6737 -1663);
DISPLAY INVISIBLE (6737 -1663);
WIRE 16 -1 (2700 2025)(2700 1975);
WIRE 16 -1 (-200 2175)(-1875 2175);
FORCEPROP 2 LAST SIG_NAME VSENSE_PVCCFA_EHV_FIVRA_CPU0_DN
J 0
(-1812 2184);
DISPLAY 0.680851 (-1812 2184);
PAINT WHITE (-1812 2184);
WIRE 16 -1 (-200 3525)(-1875 3525);
FORCEPROP 0 LAST CDS_PHYS_NET_NAME VSENSE_PVCCFA_EHV_CPU1_DP
J 0
(-1812 3566);
PAINT MONO (-1812 3566);
DISPLAY INVISIBLE (-1812 3566);
FORCEPROP 2 LAST SIG_NAME NC_CPU0_DDR01_VIEWDIG1
J 0
(-1812 3534);
DISPLAY 0.680851 (-1812 3534);
PAINT WHITE (-1812 3534);
WIRE 16 -1 (-200 3275)(-1875 3275);
FORCEPROP 2 LAST SIG_NAME NC_CPU0_DDR45_VIEWDIG0
J 0
(-1812 3284);
DISPLAY 0.680851 (-1812 3284);
PAINT WHITE (-1812 3284);
WIRE 16 -1 (-200 3125)(-1875 3125);
FORCEPROP 2 LAST SIG_NAME NC_CPU0_DDR67_VIEWDIG0
J 0
(-1812 3134);
DISPLAY 0.680851 (-1812 3134);
PAINT WHITE (-1812 3134);
WIRE 16 -1 (-200 2925)(-1875 2925);
FORCEPROP 2 LAST SIG_NAME VSENSE_PVCCFA_EHV_CPU0_DN
J 0
(-1812 2934);
DISPLAY 0.680851 (-1812 2934);
PAINT WHITE (-1812 2934);
WIRE 16 -1 (-200 2775)(-1875 2775);
FORCEPROP 2 LAST SIG_NAME VSENSE_PVCCIN_CPU0_DN
J 0
(-1812 2784);
DISPLAY 0.680851 (-1812 2784);
PAINT WHITE (-1812 2784);
WIRE 16 -1 (-200 2625)(-1875 2625);
FORCEPROP 2 LAST SIG_NAME VSENSE_PVCCINFAON_CPU0_DN
J 0
(-1812 2634);
DISPLAY 0.680851 (-1812 2634);
PAINT WHITE (-1812 2634);
WIRE 16 -1 (-200 2375)(-1875 2375);
FORCEPROP 2 LAST SIG_NAME VSENSE_PVCCD_HV_CPU0_DP
J 0
(-1812 2384);
DISPLAY 0.680851 (-1812 2384);
PAINT WHITE (-1812 2384);
WIRE 16 -1 (-200 2325)(-1875 2325);
FORCEPROP 2 LAST SIG_NAME VSENSE_PVCCD_HV_CPU0_DN
J 0
(-1812 2334);
DISPLAY 0.680851 (-1812 2334);
PAINT WHITE (-1812 2334);
WIRE 16 -1 (-200 2225)(-1875 2225);
FORCEPROP 2 LAST SIG_NAME VSENSE_PVCCFA_EHV_FIVRA_CPU0_DP
J 0
(-1812 2234);
DISPLAY 0.680851 (-1812 2234);
PAINT WHITE (-1812 2234);
WIRE 16 -1 (-200 3575)(-1875 3575);
FORCEPROP 2 LAST SIG_NAME NC_CPU0_DDR01_VIEWDIG0
J 0
(-1812 3584);
DISPLAY 0.680851 (-1812 3584);
PAINT WHITE (-1812 3584);
WIRE 16 -1 (-200 3425)(-1875 3425);
FORCEPROP 2 LAST SIG_NAME NC_CPU0_DDR23_VIEWDIG0
J 0
(-1812 3434);
DISPLAY 0.680851 (-1812 3434);
PAINT WHITE (-1812 3434);
WIRE 16 -1 (-200 3375)(-1875 3375);
FORCEPROP 0 LAST CDS_PHYS_NET_NAME VSENSE_PVCCFA_EHV_CPU1_DP
J 0
(-1812 3416);
PAINT MONO (-1812 3416);
DISPLAY INVISIBLE (-1812 3416);
FORCEPROP 2 LAST SIG_NAME NC_CPU0_DDR23_VIEWDIG1
J 0
(-1812 3384);
DISPLAY 0.680851 (-1812 3384);
PAINT WHITE (-1812 3384);
WIRE 16 -1 (3075 1325)(2550 1325);
WIRE 16 -1 (3075 1650)(3075 1325);
WIRE 16 -1 (4025 1325)(3075 1325);
FORCEPROP 2 LAST SIG_NAME DBP_CPU_MBP1_GTL_N
J 0
(3259 1334);
DISPLAY 0.680851 (3259 1334);
PAINT WHITE (3259 1334);
WIRE 16 -1 (3075 1975)(3075 1850);
WIRE 16 -1 (2700 1975)(2700 1850);
WIRE 16 -1 (2700 1975)(3075 1975);
WIRE 16 -1 (-200 2525)(-1875 2525);
FORCEPROP 2 LAST SIG_NAME H_PMAX_TRIGGER_IO_CPU0
J 0
(-1812 2534);
DISPLAY 0.680851 (-1812 2534);
PAINT WHITE (-1812 2534);
WIRE 16 -1 (-200 3225)(-1875 3225);
FORCEPROP 0 LAST CDS_PHYS_NET_NAME VSENSE_PVCCFA_EHV_CPU1_DP
J 0
(-1812 3266);
PAINT MONO (-1812 3266);
DISPLAY INVISIBLE (-1812 3266);
FORCEPROP 2 LAST SIG_NAME NC_CPU0_DDR45_VIEWDIG1
J 0
(-1812 3234);
DISPLAY 0.680851 (-1812 3234);
PAINT WHITE (-1812 3234);
WIRE 16 -1 (-200 3075)(-1875 3075);
FORCEPROP 0 LAST CDS_PHYS_NET_NAME VSENSE_PVCCFA_EHV_CPU1_DP
J 0
(-1812 3116);
PAINT MONO (-1812 3116);
DISPLAY INVISIBLE (-1812 3116);
FORCEPROP 2 LAST SIG_NAME NC_CPU0_DDR67_VIEWDIG1
J 0
(-1812 3084);
DISPLAY 0.680851 (-1812 3084);
PAINT WHITE (-1812 3084);
WIRE 16 -1 (-200 2975)(-1875 2975);
FORCEPROP 2 LAST SIG_NAME VSENSE_PVCCFA_EHV_CPU0_DP
J 0
(-1812 2984);
DISPLAY 0.680851 (-1812 2984);
PAINT WHITE (-1812 2984);
WIRE 16 -1 (-200 2675)(-1875 2675);
FORCEPROP 2 LAST SIG_NAME VSENSE_PVCCINFAON_CPU0_DP
J 0
(-1812 2684);
DISPLAY 0.680851 (-1812 2684);
PAINT WHITE (-1812 2684);
WIRE 16 -1 (-200 2825)(-1875 2825);
FORCEPROP 2 LAST SIG_NAME VSENSE_PVCCIN_CPU0_DP
J 0
(-1812 2834);
DISPLAY 0.680851 (-1812 2834);
PAINT WHITE (-1812 2834);
WIRE 16 -1 (3925 2775)(2250 2775);
FORCEPROP 2 LAST SIG_NAME NC_CPU0_LGSSPARE4
J 0
(2484 2784);
DISPLAY 0.680851 (2484 2784);
PAINT WHITE (2484 2784);
WIRE 16 -1 (3925 3575)(2250 3575);
FORCEPROP 2 LAST SIG_NAME NC_CPU0_THERMADA
J 0
(2484 3584);
DISPLAY 0.680851 (2484 3584);
PAINT WHITE (2484 3584);
WIRE 16 -1 (3925 3525)(2250 3525);
FORCEPROP 2 LAST SIG_NAME NC_CPU0_THERMADC
J 0
(2484 3534);
DISPLAY 0.680851 (2484 3534);
PAINT WHITE (2484 3534);
WIRE 16 -1 (3925 3425)(2250 3425);
FORCEPROP 2 LAST SIG_NAME TP_CPU0_A0_DEBUG_EN
J 0
(2484 3434);
DISPLAY 0.680851 (2484 3434);
PAINT WHITE (2484 3434);
WIRE 16 -1 (3925 2975)(2250 2975);
FORCEPROP 2 LAST SIG_NAME NC_CPU0_LGSSPARE0
J 0
(2484 2984);
DISPLAY 0.680851 (2484 2984);
PAINT WHITE (2484 2984);
WIRE 16 -1 (3925 2725)(2250 2725);
FORCEPROP 2 LAST SIG_NAME NC_CPU0_LGSSPARE5
J 0
(2484 2734);
DISPLAY 0.680851 (2484 2734);
PAINT WHITE (2484 2734);
WIRE 16 -1 (3925 2925)(2250 2925);
FORCEPROP 2 LAST SIG_NAME NC_CPU0_LGSSPARE1
J 0
(2484 2934);
DISPLAY 0.680851 (2484 2934);
PAINT WHITE (2484 2934);
WIRE 16 -1 (3925 2875)(2250 2875);
FORCEPROP 2 LAST SIG_NAME NC_CPU0_LGSSPARE2
J 0
(2484 2884);
DISPLAY 0.680851 (2484 2884);
PAINT WHITE (2484 2884);
WIRE 16 -1 (3925 2825)(2250 2825);
FORCEPROP 2 LAST SIG_NAME NC_CPU0_LGSSPARE3
J 0
(2484 2834);
DISPLAY 0.680851 (2484 2834);
PAINT WHITE (2484 2834);
WIRE 16 -1 (3925 3075)(2250 3075);
FORCEPROP 2 LAST SIG_NAME H_CPU0_RMCA_LVC1_R_N
J 0
(2484 3084);
DISPLAY 0.680851 (2484 3084);
PAINT WHITE (2484 3084);
WIRE 16 -1 (3625 2475)(2250 2475);
FORCEPROP 2 LAST SIG_NAME DBP_CPU0_HOOK9_MBP3_GTL_QS_R_N
J 0
(2484 2484);
DISPLAY 0.680851 (2484 2484);
PAINT WHITE (2484 2484);
WIRE 16 -1 (3625 2525)(2250 2525);
FORCEPROP 2 LAST SIG_NAME DBP_CPU0_HOOK8_MBP2_GTL_QS_R_N
J 0
(2484 2534);
DISPLAY 0.680851 (2484 2534);
PAINT WHITE (2484 2534);
WIRE 16 -1 (3625 2575)(2250 2575);
FORCEPROP 2 LAST SIG_NAME DBP_CPU0_MBP1_GTL_R_N
J 0
(2484 2584);
DISPLAY 0.680851 (2484 2584);
PAINT WHITE (2484 2584);
WIRE 16 -1 (3625 2625)(2250 2625);
FORCEPROP 2 LAST SIG_NAME DBP_CPU0_MBP0_GTL_R_N
J 0
(2484 2634);
DISPLAY 0.680851 (2484 2634);
PAINT WHITE (2484 2634);
WIRE 16 -1 (3925 3225)(2250 3225);
FORCEPROP 2 LAST SIG_NAME TP_CPU0_IFST_TRIG_LVC1_R
J 0
(2484 3234);
DISPLAY 0.680851 (2484 3234);
PAINT WHITE (2484 3234);
WIRE 16 -1 (3925 3175)(2250 3175);
FORCEPROP 2 LAST SIG_NAME TP_CPU0_IFST_KOT_LVC1_R
J 0
(2484 3184);
DISPLAY 0.680851 (2484 3184);
PAINT WHITE (2484 3184);
WIRE 16 -1 (3925 3275)(2250 3275);
FORCEPROP 2 LAST SIG_NAME TP_CPU0_IFST_DONE_LVC1_R
J 0
(2484 3284);
DISPLAY 0.680851 (2484 3284);
PAINT WHITE (2484 3284);
WIRE 16 -1 (2700 1375)(2550 1375);
WIRE 16 -1 (2700 1650)(2700 1375);
WIRE 16 -1 (4025 1375)(2700 1375);
FORCEPROP 2 LAST SIG_NAME DBP_CPU_MBP0_GTL_N
J 0
(3259 1384);
DISPLAY 0.680851 (3259 1384);
PAINT WHITE (3259 1384);
WIRE 16 -1 (5475 2525)(3825 2525);
FORCEPROP 2 LAST SIG_NAME DBP_CPU_HOOK8_MBP2_GTL_QS_N
J 0
(4509 2534);
DISPLAY 0.680851 (4509 2534);
PAINT WHITE (4509 2534);
WIRE 16 -1 (3825 2575)(5475 2575);
FORCEPROP 2 LAST SIG_NAME DBP_CPU_MBP1_GTL_N
J 0
(4509 2584);
DISPLAY 0.680851 (4509 2584);
PAINT WHITE (4509 2584);
WIRE 16 -1 (3825 2625)(5475 2625);
FORCEPROP 2 LAST SIG_NAME DBP_CPU_MBP0_GTL_N
J 0
(4509 2634);
DISPLAY 0.680851 (4509 2634);
PAINT WHITE (4509 2634);
WIRE 16 -1 (5475 1325)(4225 1325);
FORCEPROP 2 LAST SIG_NAME FM_PCH_TRIGGER1_N
J 0
(4809 1334);
DISPLAY 0.680851 (4809 1334);
PAINT WHITE (4809 1334);
WIRE 16 -1 (5475 1375)(4225 1375);
FORCEPROP 2 LAST SIG_NAME FM_PCH_TRIGGER0_N
J 0
(4809 1384);
DISPLAY 0.680851 (4809 1384);
PAINT WHITE (4809 1384);
WIRE 16 -1 (5475 2475)(3825 2475);
FORCEPROP 2 LAST SIG_NAME DBP_CPU_HOOK9_MBP3_GTL_QS_N
J 0
(4509 2484);
DISPLAY 0.680851 (4509 2484);
PAINT WHITE (4509 2484);
DOT 1 (2700 1975);
DOT 1 (2700 1375);
DOT 1 (3075 1325);
QUIT
